(kicad_pcb
	(version 20260206)
	(generator "pcbnew")
	(generator_version "10.0")
	(general
		(thickness 1.21888)
		(legacy_teardrops no)
	)
	(paper "A4")
	(title_block
		(title "timecard-v9 — TimeCard-DC-V9_EXP.PcbDoc")
		(comment 1 "Time Appliance Project (Time Card) / footprints 303-311 of 402")
	)
	(layers
		(0 "F.Cu" signal "TOP")
		(4 "In1.Cu" signal "SGND")
		(6 "In2.Cu" signal "IN1")
		(8 "In3.Cu" signal "IN2")
		(10 "In4.Cu" signal "SGND1")
		(2 "B.Cu" signal "BOTTOM")
		(9 "F.Adhes" user "F.Adhesive")
		(11 "B.Adhes" user "B.Adhesive")
		(13 "F.Paste" user "Top Paste")
		(15 "B.Paste" user "Bottom Paste")
		(5 "F.SilkS" user "Top Overlay")
		(7 "B.SilkS" user "Bottom Overlay")
		(1 "F.Mask" user "Top Solder")
		(3 "B.Mask" user "Bottom Solder")
		(17 "Dwgs.User" user "User.Drawings")
		(19 "Cmts.User" user "User.Comments")
		(21 "Eco1.User" user "User.Eco1")
		(23 "Eco2.User" user "User.Eco2")
		(25 "Edge.Cuts" user)
		(27 "Margin" user)
		(31 "F.CrtYd" user "Top Courtyard")
		(29 "B.CrtYd" user "Bottom Courtyard")
		(35 "F.Fab" user "Top Component Center")
		(33 "B.Fab" user "Bottom Component Center")
	)
	(footprint "LotusSound:IC_TPS2116"
		(layer "B.Cu")
		(at 207.7266 124.8862 180)
		(property "Reference" "U32"
			(at 9.18034 -6.934171 0)
			(unlocked yes)
			(layer "B.SilkS")
			(hide yes)
			(effects
				(font
					(size 0.762 0.762)
					(thickness 0.2032)
				)
				(justify mirror)
			)
		)
		(property "Value" "TPS2116DRLR"
			(at 15.033155 -12.638271 0)
			(unlocked yes)
			(layer "B.SilkS")
			(hide yes)
			(effects
				(font
					(size 0.762 0.762)
					(thickness 0.2032)
				)
				(justify mirror)
			)
		)
		(sheetname "09-USBUart_PPSMUX_UARTMUX")
		(sheetfile "09-USBUart_PPSMUX_UARTMUX.kicad_sch")
		(duplicate_pad_numbers_are_jumpers no)
		(fp_line
			(start 0.6 1.23)
			(end -0.6 1.23)
			(stroke
				(width 0.127)
				(type solid)
			)
			(layer "B.SilkS")
		)
		(fp_line
			(start 0.6 -1.23)
			(end -0.6 -1.23)
			(stroke
				(width 0.127)
				(type solid)
			)
			(layer "B.SilkS")
		)
		(fp_circle
			(center -1.6 0.75)
			(end -1.6 0.85)
			(stroke
				(width 0.2)
				(type solid)
			)
			(fill no)
			(layer "B.SilkS")
		)
		(pad "1" smd roundrect
			(at -0.735 0.75 180)
			(size 0.66 0.32)
			(layers "B.Cu" "B.Mask" "B.Paste")
			(roundrect_rratio 0.125)
			(net "GND")
		)
		(pad "2" smd roundrect
			(at -0.735 0.25 180)
			(size 0.66 0.32)
			(layers "B.Cu" "B.Mask" "B.Paste")
			(roundrect_rratio 0.125)
			(net "GNSS2_P3V3")
		)
		(pad "3" smd roundrect
			(at -0.735 -0.25 180)
			(size 0.66 0.32)
			(layers "B.Cu" "B.Mask" "B.Paste")
			(roundrect_rratio 0.125)
			(net "+3.3V")
		)
		(pad "4" smd roundrect
			(at -0.735 -0.75 180)
			(size 0.66 0.32)
			(layers "B.Cu" "B.Mask" "B.Paste")
			(roundrect_rratio 0.125)
			(net "NetR49_1")
		)
		(pad "5" smd roundrect
			(at 0.735 -0.75 180)
			(size 0.66 0.32)
			(layers "B.Cu" "B.Mask" "B.Paste")
			(roundrect_rratio 0.125)
			(net "+3.3V")
		)
		(pad "6" smd roundrect
			(at 0.735 -0.25 180)
			(size 0.66 0.32)
			(layers "B.Cu" "B.Mask" "B.Paste")
			(roundrect_rratio 0.125)
			(net "FTDI_P3V3")
		)
		(pad "7" smd roundrect
			(at 0.735 0.25 180)
			(size 0.66 0.32)
			(layers "B.Cu" "B.Mask" "B.Paste")
			(roundrect_rratio 0.125)
			(net "GNSS2_P3V3")
		)
		(pad "8" smd roundrect
			(at 0.735 0.75 180)
			(size 0.66 0.32)
			(layers "B.Cu" "B.Mask" "B.Paste")
			(roundrect_rratio 0.125)
		)
	)
	(footprint "Vault:RESC1608X55X30NL15T15"
		(layer "B.Cu")
		(at 79.4216 56.2162 180)
		(property "Reference" "R39"
			(at -2.4714 -0.026931 0)
			(unlocked yes)
			(layer "B.SilkS")
			(effects
				(font
					(size 0.762 0.762)
					(thickness 0.2286)
				)
				(justify mirror)
			)
		)
		(property "Value" "200 OHM"
			(at -2.935471 -4.78626 90)
			(unlocked yes)
			(layer "B.SilkS")
			(hide yes)
			(effects
				(font
					(size 0.762 0.762)
					(thickness 0.2286)
				)
				(justify mirror)
			)
		)
		(sheetname "02-USER_IO_STATUS")
		(sheetfile "02-USER_IO_STATUS.kicad_sch")
		(duplicate_pad_numbers_are_jumpers no)
		(pad "1" smd rect
			(at -0.675 0 90)
			(size 0.95 0.8)
			(layers "B.Cu" "B.Mask" "B.Paste")
			(net "LED4")
		)
		(pad "2" smd rect
			(at 0.675 0 90)
			(size 0.95 0.8)
			(layers "B.Cu" "B.Mask" "B.Paste")
			(net "NetD11_1")
		)
	)
	(footprint "Vault:RESC1005X40X25LL05T05"
		(layer "B.Cu")
		(at 112.58072 85.9662 180)
		(property "Reference" "R58"
			(at 0.23052 -6.523069 180)
			(unlocked yes)
			(layer "B.SilkS")
			(effects
				(font
					(size 0.762 0.762)
					(thickness 0.2286)
				)
				(justify mirror)
			)
		)
		(property "Value" "4.7K_0402"
			(at -3.024401 -2.374035 90)
			(unlocked yes)
			(layer "B.SilkS")
			(hide yes)
			(effects
				(font
					(size 0.762 0.762)
					(thickness 0.2286)
				)
				(justify mirror)
			)
		)
		(sheetname "05-GPS_IMU_SENSORS")
		(sheetfile "05-GPS_IMU_SENSORS.kicad_sch")
		(duplicate_pad_numbers_are_jumpers no)
		(pad "1" smd rect
			(at -0.4 0 90)
			(size 0.45 0.45)
			(layers "B.Cu" "B.Mask" "B.Paste")
			(net "BNO_P3V3")
		)
		(pad "2" smd rect
			(at 0.4 0 90)
			(size 0.45 0.45)
			(layers "B.Cu" "B.Mask" "B.Paste")
			(net "NetR58_2")
		)
	)
	(footprint "Vault:RESC1005X40X25LL05T10"
		(layer "B.Cu")
		(at 221.9216 100.1162 90)
		(property "Reference" "R140"
			(at 0.2032 1.073069 270)
			(unlocked yes)
			(layer "B.SilkS")
			(effects
				(font
					(size 0.762 0.762)
					(thickness 0.2032)
				)
				(justify mirror)
			)
		)
		(property "Value" "10K_1%_0402"
			(at -2.579871 -8.036515 0)
			(unlocked yes)
			(layer "B.SilkS")
			(hide yes)
			(effects
				(font
					(size 0.762 0.762)
					(thickness 0.2032)
				)
				(justify mirror)
			)
		)
		(sheetname "08-DIPSwitches_I2C")
		(sheetfile "08-DIPSwitches_I2C.kicad_sch")
		(duplicate_pad_numbers_are_jumpers no)
		(pad "1" smd rect
			(at -0.375 0)
			(size 0.45 0.5)
			(layers "B.Cu" "B.Mask" "B.Paste")
			(net "+3.3V")
		)
		(pad "2" smd rect
			(at 0.375 0)
			(size 0.45 0.5)
			(layers "B.Cu" "B.Mask" "B.Paste")
			(net "DIP_SW_GPS2_SEL")
		)
	)
	(footprint "Vault:FP-711AT-MFG"
		(layer "B.Cu")
		(at 221.8933 126.23428)
		(property "Reference" "U33"
			(at 0.27272 -1.591149 0)
			(unlocked yes)
			(layer "B.SilkS")
			(effects
				(font
					(size 0.762 0.762)
					(thickness 0.254)
				)
				(justify mirror)
			)
		)
		(property "Value" "NCP176AMX330TCG"
			(at 10.067525 -2.579871 180)
			(unlocked yes)
			(layer "B.SilkS")
			(hide yes)
			(effects
				(font
					(size 0.762 0.762)
					(thickness 0.254)
				)
				(justify mirror)
			)
		)
		(sheetname "09-USBUart_PPSMUX_UARTMUX")
		(sheetfile "09-USBUart_PPSMUX_UARTMUX.kicad_sch")
		(duplicate_pad_numbers_are_jumpers no)
		(fp_line
			(start -0.625 0.925)
			(end 0.625 0.925)
			(stroke
				(width 0.2)
				(type solid)
			)
			(layer "B.SilkS")
		)
		(fp_line
			(start -0.615 -0.925)
			(end 0.635 -0.925)
			(stroke
				(width 0.2)
				(type solid)
			)
			(layer "B.SilkS")
		)
		(fp_circle
			(center -1.225 0.4)
			(end -1.225 0.275)
			(stroke
				(width 0.25)
				(type solid)
			)
			(fill no)
			(layer "B.SilkS")
		)
		(fp_line
			(start -0.8 -0.725)
			(end 0.8 -0.725)
			(stroke
				(width 0.2)
				(type solid)
			)
			(layer "B.CrtYd")
		)
		(fp_line
			(start -0.8 0.725)
			(end -0.8 -0.725)
			(stroke
				(width 0.2)
				(type solid)
			)
			(layer "B.CrtYd")
		)
		(fp_line
			(start -0.8 0.725)
			(end 0.8 0.725)
			(stroke
				(width 0.2)
				(type solid)
			)
			(layer "B.CrtYd")
		)
		(fp_line
			(start 0.8 0.725)
			(end 0.8 -0.725)
			(stroke
				(width 0.2)
				(type solid)
			)
			(layer "B.CrtYd")
		)
		(fp_line
			(start -0.8 -0.725)
			(end 0.8 -0.725)
			(stroke
				(width 0.2)
				(type solid)
			)
			(layer "B.Fab")
		)
		(fp_line
			(start -0.8 0.725)
			(end -0.8 -0.725)
			(stroke
				(width 0.2)
				(type solid)
			)
			(layer "B.Fab")
		)
		(fp_line
			(start -0.8 0.725)
			(end 0.8 0.725)
			(stroke
				(width 0.2)
				(type solid)
			)
			(layer "B.Fab")
		)
		(fp_line
			(start -0.5 0)
			(end 0.5 0)
			(stroke
				(width 0.1)
				(type solid)
			)
			(layer "B.Fab")
		)
		(fp_line
			(start 0 0.5)
			(end 0 -0.5)
			(stroke
				(width 0.1)
				(type solid)
			)
			(layer "B.Fab")
		)
		(fp_line
			(start 0.8 0.725)
			(end 0.8 -0.725)
			(stroke
				(width 0.2)
				(type solid)
			)
			(layer "B.Fab")
		)
		(fp_text user "${REFERENCE}"
			(at 0 -0.28425 180)
			(unlocked yes)
			(layer "B.Fab")
			(effects
				(font
					(face "Arial")
					(size 0.63 0.63)
					(thickness 0.1)
				)
				(justify left bottom mirror)
			)
		)
		(pad "1" smd rect
			(at -0.515 0.4)
			(size 0.37 0.24)
			(layers "B.Cu" "B.Mask" "B.Paste")
			(net "FTDI_P3V3")
			(solder_mask_margin 0)
			(solder_paste_margin 0)
		)
		(pad "2" smd rect
			(at -0.515 0)
			(size 0.37 0.24)
			(layers "B.Cu" "B.Mask" "B.Paste")
			(net "FTDI_P3V3")
			(solder_mask_margin 0)
			(solder_paste_margin 0)
		)
		(pad "3" smd rect
			(at -0.515 -0.4)
			(size 0.37 0.24)
			(layers "B.Cu" "B.Mask" "B.Paste")
			(net "GND")
			(solder_mask_margin 0)
			(solder_paste_margin 0)
		)
		(pad "4" smd rect
			(at 0.515 -0.4)
			(size 0.37 0.24)
			(layers "B.Cu" "B.Mask" "B.Paste")
			(net "FTDI_VBUS")
			(solder_mask_margin 0)
			(solder_paste_margin 0)
		)
		(pad "5" smd rect
			(at 0.515 0)
			(size 0.37 0.24)
			(layers "B.Cu" "B.Mask" "B.Paste")
			(solder_mask_margin 0)
			(solder_paste_margin 0)
		)
		(pad "6" smd rect
			(at 0.515 0.4)
			(size 0.37 0.24)
			(layers "B.Cu" "B.Mask" "B.Paste")
			(net "FTDI_VBUS")
			(solder_mask_margin 0)
			(solder_paste_margin 0)
		)
		(pad "7" smd rect
			(at 0 0)
			(size 0.4 1.08)
			(layers "B.Cu" "B.Mask" "B.Paste")
			(net "GND")
			(solder_mask_margin 0)
			(solder_paste_margin 0)
		)
	)
	(footprint "Vault:FP-0402-L_1_0_1-W_0_5_0_1-IPC_C"
		(layer "B.Cu")
		(at 193.50119 131.4145 -90)
		(property "Reference" "C108"
			(at 0.2049 1.452669 90)
			(unlocked yes)
			(layer "B.SilkS")
			(effects
				(font
					(size 0.762 0.762)
					(thickness 0.2032)
				)
				(justify mirror)
			)
		)
		(property "Value" "0.1uF_25V_0402"
			(at -2.465551 -9.813805 180)
			(unlocked yes)
			(layer "B.SilkS")
			(hide yes)
			(effects
				(font
					(size 0.762 0.762)
					(thickness 0.2032)
				)
				(justify mirror)
			)
		)
		(sheetname "11-M2_RCB_MUX")
		(sheetfile "11-M2_RCB_MUX.kicad_sch")
		(duplicate_pad_numbers_are_jumpers no)
		(fp_line
			(start 0.65607 0.7)
			(end -0.65607 0.7)
			(stroke
				(width 0.2)
				(type solid)
			)
			(layer "B.SilkS")
		)
		(fp_line
			(start 0.65607 -0.7)
			(end -0.65607 -0.7)
			(stroke
				(width 0.2)
				(type solid)
			)
			(layer "B.SilkS")
		)
		(fp_line
			(start -0.75607 0.4)
			(end -0.75607 -0.4)
			(stroke
				(width 0.2)
				(type solid)
			)
			(layer "B.CrtYd")
		)
		(fp_line
			(start 0.75607 0.4)
			(end -0.75607 0.4)
			(stroke
				(width 0.2)
				(type solid)
			)
			(layer "B.CrtYd")
		)
		(fp_line
			(start 0.75607 0.4)
			(end 0.75607 -0.4)
			(stroke
				(width 0.2)
				(type solid)
			)
			(layer "B.CrtYd")
		)
		(fp_line
			(start 0.75607 -0.4)
			(end -0.75607 -0.4)
			(stroke
				(width 0.2)
				(type solid)
			)
			(layer "B.CrtYd")
		)
		(fp_line
			(start 0 0.5)
			(end 0 -0.5)
			(stroke
				(width 0.1)
				(type solid)
			)
			(layer "B.Fab")
		)
		(fp_line
			(start -0.75607 0.4)
			(end -0.75607 -0.4)
			(stroke
				(width 0.2)
				(type solid)
			)
			(layer "B.Fab")
		)
		(fp_line
			(start 0.75607 0.4)
			(end -0.75607 0.4)
			(stroke
				(width 0.2)
				(type solid)
			)
			(layer "B.Fab")
		)
		(fp_line
			(start 0.75607 0.4)
			(end 0.75607 -0.4)
			(stroke
				(width 0.2)
				(type solid)
			)
			(layer "B.Fab")
		)
		(fp_line
			(start 0.5 0)
			(end -0.5 0)
			(stroke
				(width 0.1)
				(type solid)
			)
			(layer "B.Fab")
		)
		(fp_line
			(start 0.75607 -0.4)
			(end -0.75607 -0.4)
			(stroke
				(width 0.2)
				(type solid)
			)
			(layer "B.Fab")
		)
		(fp_text user "${REFERENCE}"
			(at -0.00001 -0.09601 90)
			(unlocked yes)
			(layer "B.Fab")
			(effects
				(font
					(face "Arial")
					(size 0.63 0.63)
					(thickness 0.1)
				)
				(justify left bottom mirror)
			)
		)
		(pad "1" smd rect
			(at -0.36554 0 270)
			(size 0.58106 0.51213)
			(layers "B.Cu" "B.Mask" "B.Paste")
			(net "+3.3V")
			(solder_mask_margin 0)
			(solder_paste_margin 0)
		)
		(pad "2" smd rect
			(at 0.36554 0 270)
			(size 0.58106 0.51213)
			(layers "B.Cu" "B.Mask" "B.Paste")
			(net "GND")
			(solder_mask_margin 0)
			(solder_paste_margin 0)
		)
	)
	(footprint "Vault:FP-0603-L_1_6_0_2-W_0_8_0-MFG"
		(layer "B.Cu")
		(at 114.0216 80.9162 -90)
		(property "Reference" "C6"
			(at -3 -0.493345 90)
			(unlocked yes)
			(layer "B.SilkS")
			(effects
				(font
					(size 0.762 0.762)
					(thickness 0.2286)
				)
				(justify left bottom mirror)
			)
		)
		(property "Value" "10uF_16V_0603"
			(at 5.449845 12.8601 0)
			(unlocked yes)
			(layer "B.SilkS")
			(hide yes)
			(effects
				(font
					(size 0.762 0.762)
					(thickness 0.2286)
				)
				(justify left bottom mirror)
			)
		)
		(sheetname "05-GPS_IMU_SENSORS")
		(sheetfile "05-GPS_IMU_SENSORS.kicad_sch")
		(duplicate_pad_numbers_are_jumpers no)
		(fp_line
			(start 0.9 0.825)
			(end -0.9 0.825)
			(stroke
				(width 0.2)
				(type solid)
			)
			(layer "B.SilkS")
		)
		(fp_line
			(start 0.9 -0.825)
			(end -0.9 -0.825)
			(stroke
				(width 0.2)
				(type solid)
			)
			(layer "B.SilkS")
		)
		(fp_line
			(start -1.15 0.6)
			(end -1.15 -0.6)
			(stroke
				(width 0.2)
				(type solid)
			)
			(layer "B.CrtYd")
		)
		(fp_line
			(start 1.15 0.6)
			(end -1.15 0.6)
			(stroke
				(width 0.2)
				(type solid)
			)
			(layer "B.CrtYd")
		)
		(fp_line
			(start 1.15 0.6)
			(end 1.15 -0.6)
			(stroke
				(width 0.2)
				(type solid)
			)
			(layer "B.CrtYd")
		)
		(fp_line
			(start 1.15 -0.6)
			(end -1.15 -0.6)
			(stroke
				(width 0.2)
				(type solid)
			)
			(layer "B.CrtYd")
		)
		(fp_line
			(start -1.15 0.6)
			(end -1.15 -0.6)
			(stroke
				(width 0.2)
				(type solid)
			)
			(layer "B.Fab")
		)
		(fp_line
			(start 1.15 0.6)
			(end -1.15 0.6)
			(stroke
				(width 0.2)
				(type solid)
			)
			(layer "B.Fab")
		)
		(fp_line
			(start 1.15 0.6)
			(end 1.15 -0.6)
			(stroke
				(width 0.2)
				(type solid)
			)
			(layer "B.Fab")
		)
		(fp_line
			(start 0 0.5)
			(end 0 -0.5)
			(stroke
				(width 0.1)
				(type solid)
			)
			(layer "B.Fab")
		)
		(fp_line
			(start 0.5 0)
			(end -0.5 0)
			(stroke
				(width 0.1)
				(type solid)
			)
			(layer "B.Fab")
		)
		(fp_line
			(start 1.15 -0.6)
			(end -1.15 -0.6)
			(stroke
				(width 0.2)
				(type solid)
			)
			(layer "B.Fab")
		)
		(fp_text user "${REFERENCE}"
			(at -0.00002 -0.09602 90)
			(unlocked yes)
			(layer "B.Fab")
			(effects
				(font
					(face "Arial")
					(size 0.63 0.63)
					(thickness 0.1)
				)
				(justify left bottom mirror)
			)
		)
		(pad "1" smd rect
			(at -0.7 0 270)
			(size 0.7 0.7)
			(layers "B.Cu" "B.Mask" "B.Paste")
			(net "+5.0V")
			(solder_mask_margin 0)
			(solder_paste_margin 0)
		)
		(pad "2" smd rect
			(at 0.7 0 270)
			(size 0.7 0.7)
			(layers "B.Cu" "B.Mask" "B.Paste")
			(net "GND")
			(solder_mask_margin 0)
			(solder_paste_margin 0)
		)
	)
	(footprint "Vault:FP-MK212BG-MFG"
		(layer "B.Cu")
		(at 213.6216 139.0162 180)
		(property "Reference" "C56"
			(at 0.8286 1.273079 0)
			(unlocked yes)
			(layer "B.SilkS")
			(effects
				(font
					(size 0.762 0.762)
					(thickness 0.2286)
				)
				(justify mirror)
			)
		)
		(property "Value" "10uF"
			(at -3.240271 -2.22164 90)
			(unlocked yes)
			(layer "B.SilkS")
			(hide yes)
			(effects
				(font
					(size 0.762 0.762)
					(thickness 0.2286)
				)
				(justify mirror)
			)
		)
		(sheetname "05-GPS_IMU_SENSORS")
		(sheetfile "05-GPS_IMU_SENSORS.kicad_sch")
		(duplicate_pad_numbers_are_jumpers no)
		(fp_line
			(start 0.125 0.725)
			(end -0.125 0.725)
			(stroke
				(width 0.2)
				(type solid)
			)
			(layer "B.SilkS")
		)
		(fp_line
			(start 0.125 -0.725)
			(end -0.125 -0.725)
			(stroke
				(width 0.2)
				(type solid)
			)
			(layer "B.SilkS")
		)
		(fp_line
			(start 1.6 0.825)
			(end -1.6 0.825)
			(stroke
				(width 0.2)
				(type solid)
			)
			(layer "B.CrtYd")
		)
		(fp_line
			(start 1.6 -0.825)
			(end 1.6 0.825)
			(stroke
				(width 0.2)
				(type solid)
			)
			(layer "B.CrtYd")
		)
		(fp_line
			(start 1.6 -0.825)
			(end -1.6 -0.825)
			(stroke
				(width 0.2)
				(type solid)
			)
			(layer "B.CrtYd")
		)
		(fp_line
			(start -1.6 -0.825)
			(end -1.6 0.825)
			(stroke
				(width 0.2)
				(type solid)
			)
			(layer "B.CrtYd")
		)
		(fp_line
			(start 1.6 0.825)
			(end -1.6 0.825)
			(stroke
				(width 0.2)
				(type solid)
			)
			(layer "B.Fab")
		)
		(fp_line
			(start 1.6 -0.825)
			(end 1.6 0.825)
			(stroke
				(width 0.2)
				(type solid)
			)
			(layer "B.Fab")
		)
		(fp_line
			(start 1.6 -0.825)
			(end -1.6 -0.825)
			(stroke
				(width 0.2)
				(type solid)
			)
			(layer "B.Fab")
		)
		(fp_line
			(start 0.5 0)
			(end -0.5 0)
			(stroke
				(width 0.1)
				(type solid)
			)
			(layer "B.Fab")
		)
		(fp_line
			(start 0 -0.5)
			(end 0 0.5)
			(stroke
				(width 0.1)
				(type solid)
			)
			(layer "B.Fab")
		)
		(fp_line
			(start -1.6 -0.825)
			(end -1.6 0.825)
			(stroke
				(width 0.2)
				(type solid)
			)
			(layer "B.Fab")
		)
		(fp_text user "${REFERENCE}"
			(at -0.00001 -0.09602 360)
			(unlocked yes)
			(layer "B.Fab")
			(effects
				(font
					(face "Arial")
					(size 0.63 0.63)
					(thickness 0.1)
				)
				(justify left bottom mirror)
			)
		)
		(pad "1" smd rect
			(at -1 0 180)
			(size 1 1.25)
			(layers "B.Cu" "B.Mask" "B.Paste")
			(net "GNSS2_P5V0")
			(solder_mask_margin 0)
			(solder_paste_margin 0)
		)
		(pad "2" smd rect
			(at 1 0 180)
			(size 1 1.25)
			(layers "B.Cu" "B.Mask" "B.Paste")
			(net "GND")
			(solder_mask_margin 0)
			(solder_paste_margin 0)
		)
	)
	(footprint "Capacitors:CAPC1005X06N"
		(layer "B.Cu")
		(at 136.4956 151.7886 90)
		(property "Reference" "C50"
			(at 2.41349 -0.766255 270)
			(unlocked yes)
			(layer "B.SilkS")
			(effects
				(font
					(size 0.762 0.762)
					(thickness 0.2286)
				)
				(justify left bottom mirror)
			)
		)
		(property "Value" "CAP_0402_0.1UF_50V"
			(at -3.382645 0.2921 0)
			(unlocked yes)
			(layer "B.SilkS")
			(hide yes)
			(effects
				(font
					(size 0.762 0.762)
					(thickness 0.2286)
				)
				(justify left bottom mirror)
			)
		)
		(sheetname "04-PCIe_JTAG")
		(sheetfile "04-PCIe_JTAG.kicad_sch")
		(duplicate_pad_numbers_are_jumpers no)
		(pad "1" smd rect
			(at -0.43 0)
			(size 0.64 0.68)
			(layers "B.Cu" "B.Mask" "B.Paste")
			(net "NetC50_1")
		)
		(pad "2" smd rect
			(at 0.43 0)
			(size 0.64 0.68)
			(layers "B.Cu" "B.Mask" "B.Paste")
			(net "PCIE_TX2_P")
		)
	)
)
